(kicad_pcb
	(version 20241229)
	(generator "pcbnew")
	(generator_version "9.0")
	(general
		(thickness 1.61)
		(legacy_teardrops no)
	)
	(paper "A3")
	(title_block
		(title "SO-DIMM DDR5 Tester")
		(date "2025-11-26")
		(rev "1.3.0")
		(comment 9 "footprints 528-534 of 627")
	)
	(layers
		(0 "F.Cu" signal)
		(4 "In1.Cu" power)
		(6 "In2.Cu" mixed)
		(8 "In3.Cu" power)
		(10 "In4.Cu" mixed)
		(12 "In5.Cu" power)
		(14 "In6.Cu" mixed)
		(16 "In7.Cu" power)
		(18 "In8.Cu" power)
		(20 "In9.Cu" mixed)
		(22 "In10.Cu" power)
		(2 "B.Cu" signal)
		(9 "F.Adhes" user "F.Adhesive")
		(11 "B.Adhes" user "B.Adhesive")
		(13 "F.Paste" user)
		(15 "B.Paste" user)
		(5 "F.SilkS" user "F.Silkscreen")
		(7 "B.SilkS" user "B.Silkscreen")
		(1 "F.Mask" user)
		(3 "B.Mask" user)
		(17 "Dwgs.User" user "User.Drawings")
		(19 "Cmts.User" user "User.Comments")
		(21 "Eco1.User" user "User.Eco1")
		(23 "Eco2.User" user "User.Eco2")
		(25 "Edge.Cuts" user)
		(27 "Margin" user)
		(31 "F.CrtYd" user "F.Courtyard")
		(29 "B.CrtYd" user "B.Courtyard")
		(35 "F.Fab" user)
		(33 "B.Fab" user)
	)
	(footprint "antmicro-footprints:R_0402_1005Metric"
		(layer "B.Cu")
		(at 196.7 161.95 180)
		(descr "Resistor SMD 0402")
		(tags "resistor SMD 0402")
		(property "Reference" "R158"
			(at -1.1 0.7 0)
			(layer "B.SilkS")
			(effects
				(font
					(size 0.7 0.7)
					(thickness 0.15)
				)
				(justify left bottom mirror)
			)
		)
		(property "Value" "R_0R_0402"
			(at -1.011843 -1.772047 0)
			(layer "B.Fab")
			(effects
				(font
					(size 0.7 0.7)
					(thickness 0.15)
				)
				(justify left bottom mirror)
			)
		)
		(property "Datasheet" "https://industrial.panasonic.com/cdbs/www-data/pdf/RDA0000/AOA0000C301.pdf"
			(at 0 0 180)
			(layer "F.Fab")
			(hide yes)
			(effects
				(font
					(size 1.27 1.27)
					(thickness 0.15)
				)
			)
		)
		(property "Author" "Antmicro"
			(at 393.4 323.9 0)
			(layer "B.Fab")
			(hide yes)
			(effects
				(font
					(size 1 1)
					(thickness 0.15)
				)
				(justify mirror)
			)
		)
		(property "Current" "1A"
			(at 393.4 323.9 0)
			(layer "B.Fab")
			(hide yes)
			(effects
				(font
					(size 1 1)
					(thickness 0.15)
				)
				(justify mirror)
			)
		)
		(property "License" "Apache-2.0"
			(at 393.4 323.9 0)
			(layer "B.Fab")
			(hide yes)
			(effects
				(font
					(size 1 1)
					(thickness 0.15)
				)
				(justify mirror)
			)
		)
		(property "MPN" "ERJ2GE0R00X"
			(at 393.4 323.9 0)
			(layer "B.Fab")
			(hide yes)
			(effects
				(font
					(size 1 1)
					(thickness 0.15)
				)
				(justify mirror)
			)
		)
		(property "Manufacturer" "Panasonic"
			(at 393.4 323.9 0)
			(layer "B.Fab")
			(hide yes)
			(effects
				(font
					(size 1 1)
					(thickness 0.15)
				)
				(justify mirror)
			)
		)
		(property "Tolerance" ""
			(at 393.4 323.9 0)
			(layer "B.Fab")
			(hide yes)
			(effects
				(font
					(size 1 1)
					(thickness 0.15)
				)
				(justify mirror)
			)
		)
		(property "Val" "0R"
			(at 393.4 323.9 0)
			(layer "B.Fab")
			(hide yes)
			(effects
				(font
					(size 1 1)
					(thickness 0.15)
				)
				(justify mirror)
			)
		)
		(sheetname "/Supply/")
		(sheetfile "supply.kicad_sch")
		(attr exclude_from_pos_files exclude_from_bom dnp)
		(fp_rect
			(start -0.93 0.47)
			(end 0.93 -0.47)
			(stroke
				(width 0.05)
				(type solid)
			)
			(fill no)
			(layer "B.CrtYd")
		)
		(fp_rect
			(start -0.5 0.25)
			(end 0.5 -0.25)
			(stroke
				(width 0.15)
				(type solid)
			)
			(fill no)
			(layer "B.Fab")
		)
		(pad "1" smd roundrect
			(at -0.485 0 180)
			(size 0.59 0.64)
			(layers "B.Cu" "B.Mask" "B.Paste")
			(roundrect_rratio 0.25)
			(net 1 "GND")
			(pintype "passive")
		)
		(pad "2" smd roundrect
			(at 0.485 0 180)
			(size 0.59 0.64)
			(layers "B.Cu" "B.Mask" "B.Paste")
			(roundrect_rratio 0.25)
			(net 208 "/Supply/FB6")
			(pintype "passive")
		)
	)
	(footprint "antmicro-footprints:TP_SMD_1mm"
		(layer "B.Cu")
		(at 179.4 189.5 180)
		(property "Reference" "TP70"
			(at -3.5 -0.3 0)
			(layer "B.SilkS")
			(effects
				(font
					(size 0.7 0.7)
					(thickness 0.15)
				)
				(justify left bottom mirror)
			)
		)
		(property "Value" "TP_1mm_SMD"
			(at 0 -1.4 0)
			(layer "B.Fab")
			(effects
				(font
					(size 0.7 0.7)
					(thickness 0.15)
				)
				(justify left bottom mirror)
			)
		)
		(property "MPN" ""
			(at 0 0 0)
			(unlocked yes)
			(layer "B.Fab")
			(hide yes)
			(effects
				(font
					(size 1 1)
					(thickness 0.15)
				)
				(justify mirror)
			)
		)
		(property "Manufacturer" ""
			(at 0 0 0)
			(unlocked yes)
			(layer "B.Fab")
			(hide yes)
			(effects
				(font
					(size 1 1)
					(thickness 0.15)
				)
				(justify mirror)
			)
		)
		(property "Author" "Antmicro"
			(at 0 0 0)
			(unlocked yes)
			(layer "B.Fab")
			(hide yes)
			(effects
				(font
					(size 1 1)
					(thickness 0.15)
				)
				(justify mirror)
			)
		)
		(property "License" "Apache-2.0"
			(at 0 0 0)
			(unlocked yes)
			(layer "B.Fab")
			(hide yes)
			(effects
				(font
					(size 1 1)
					(thickness 0.15)
				)
				(justify mirror)
			)
		)
		(sheetname "/I^{2}C/")
		(sheetfile "i2c.kicad_sch")
		(attr exclude_from_pos_files)
		(fp_circle
			(center 0 0)
			(end 0.6 0)
			(stroke
				(width 0.05)
				(type default)
			)
			(fill no)
			(layer "B.CrtYd")
		)
		(fp_text user "Author: Antmicro"
			(at -0.5 -4 0)
			(layer "B.Fab")
			(effects
				(font
					(size 0.7 0.7)
					(thickness 0.15)
				)
				(justify left bottom mirror)
			)
		)
		(fp_text user "${REFERENCE}"
			(at -0.5 -2.8 0)
			(layer "B.Fab")
			(effects
				(font
					(size 0.7 0.7)
					(thickness 0.15)
				)
				(justify left bottom mirror)
			)
		)
		(fp_text user "License: Apache-2.0"
			(at -0.5 -5.2 0)
			(layer "B.Fab")
			(effects
				(font
					(size 0.7 0.7)
					(thickness 0.15)
				)
				(justify left bottom mirror)
			)
		)
		(pad "1" smd circle
			(at 0 0 180)
			(size 1 1)
			(layers "B.Cu" "B.Mask")
			(net 762 "Net-(U34-SCL)")
			(pinfunction "1")
			(pintype "passive")
		)
	)
	(footprint "antmicro-footprints:R_0402_1005Metric"
		(layer "B.Cu")
		(at 108.4 142.4 90)
		(descr "Resistor SMD 0402")
		(tags "resistor SMD 0402")
		(property "Reference" "R32"
			(at 3.044968 0.254606 270)
			(layer "B.SilkS")
			(effects
				(font
					(size 0.7 0.7)
					(thickness 0.15)
				)
				(justify left bottom mirror)
			)
		)
		(property "Value" "R_0R_0402"
			(at -1.011843 -1.772047 270)
			(layer "B.Fab")
			(effects
				(font
					(size 0.7 0.7)
					(thickness 0.15)
				)
				(justify left bottom mirror)
			)
		)
		(property "Datasheet" "https://industrial.panasonic.com/cdbs/www-data/pdf/RDA0000/AOA0000C301.pdf"
			(at 0 0 90)
			(layer "F.Fab")
			(hide yes)
			(effects
				(font
					(size 1.27 1.27)
					(thickness 0.15)
				)
			)
		)
		(property "Author" "Antmicro"
			(at 250.8 34 0)
			(layer "B.Fab")
			(hide yes)
			(effects
				(font
					(size 1 1)
					(thickness 0.15)
				)
				(justify mirror)
			)
		)
		(property "Current" "1A"
			(at 250.8 34 0)
			(layer "B.Fab")
			(hide yes)
			(effects
				(font
					(size 1 1)
					(thickness 0.15)
				)
				(justify mirror)
			)
		)
		(property "License" "Apache-2.0"
			(at 250.8 34 0)
			(layer "B.Fab")
			(hide yes)
			(effects
				(font
					(size 1 1)
					(thickness 0.15)
				)
				(justify mirror)
			)
		)
		(property "MPN" "ERJ2GE0R00X"
			(at 250.8 34 0)
			(layer "B.Fab")
			(hide yes)
			(effects
				(font
					(size 1 1)
					(thickness 0.15)
				)
				(justify mirror)
			)
		)
		(property "Manufacturer" "Panasonic"
			(at 250.8 34 0)
			(layer "B.Fab")
			(hide yes)
			(effects
				(font
					(size 1 1)
					(thickness 0.15)
				)
				(justify mirror)
			)
		)
		(property "Tolerance" ""
			(at 250.8 34 0)
			(layer "B.Fab")
			(hide yes)
			(effects
				(font
					(size 1 1)
					(thickness 0.15)
				)
				(justify mirror)
			)
		)
		(property "Val" "0R"
			(at 250.8 34 0)
			(layer "B.Fab")
			(hide yes)
			(effects
				(font
					(size 1 1)
					(thickness 0.15)
				)
				(justify mirror)
			)
		)
		(sheetname "/DDR5 SODIMM/")
		(sheetfile "ddr5-sodimm.kicad_sch")
		(attr exclude_from_pos_files exclude_from_bom dnp)
		(fp_rect
			(start -0.93 0.47)
			(end 0.93 -0.47)
			(stroke
				(width 0.05)
				(type solid)
			)
			(fill no)
			(layer "B.CrtYd")
		)
		(fp_rect
			(start -0.5 0.25)
			(end 0.5 -0.25)
			(stroke
				(width 0.15)
				(type solid)
			)
			(fill no)
			(layer "B.Fab")
		)
		(pad "1" smd roundrect
			(at -0.485 0 90)
			(size 0.59 0.64)
			(layers "B.Cu" "B.Mask" "B.Paste")
			(roundrect_rratio 0.25)
			(net 1 "GND")
			(pintype "passive")
		)
		(pad "2" smd roundrect
			(at 0.485 0 90)
			(size 0.59 0.64)
			(layers "B.Cu" "B.Mask" "B.Paste")
			(roundrect_rratio 0.25)
			(net 137 "/DDR5 SODIMM/RFU1")
			(pintype "passive")
		)
	)
	(footprint "antmicro-footprints:R_0402_1005Metric"
		(layer "B.Cu")
		(at 195.415 147.851)
		(descr "Resistor SMD 0402")
		(tags "resistor SMD 0402")
		(property "Reference" "R184"
			(at -1.122484 0.772697 180)
			(layer "B.SilkS")
			(hide yes)
			(effects
				(font
					(size 0.7 0.7)
					(thickness 0.15)
				)
				(justify left bottom mirror)
			)
		)
		(property "Value" "R_47k_0402"
			(at -1.011843 -1.772047 180)
			(layer "B.Fab")
			(effects
				(font
					(size 0.7 0.7)
					(thickness 0.15)
				)
				(justify left bottom mirror)
			)
		)
		(property "Datasheet" "https://www.bourns.com/docs/product-datasheets/cr.pdf"
			(at 0 0 0)
			(layer "F.Fab")
			(hide yes)
			(effects
				(font
					(size 1.27 1.27)
					(thickness 0.15)
				)
			)
		)
		(property "Author" "Antmicro"
			(at 0 0 0)
			(layer "B.Fab")
			(hide yes)
			(effects
				(font
					(size 1 1)
					(thickness 0.15)
				)
				(justify mirror)
			)
		)
		(property "License" "Apache-2.0"
			(at 0 0 0)
			(layer "B.Fab")
			(hide yes)
			(effects
				(font
					(size 1 1)
					(thickness 0.15)
				)
				(justify mirror)
			)
		)
		(property "MPN" "CR0402-FX-4702GLF"
			(at 0 0 0)
			(layer "B.Fab")
			(hide yes)
			(effects
				(font
					(size 1 1)
					(thickness 0.15)
				)
				(justify mirror)
			)
		)
		(property "Manufacturer" "Bourns"
			(at 0 0 0)
			(layer "B.Fab")
			(hide yes)
			(effects
				(font
					(size 1 1)
					(thickness 0.15)
				)
				(justify mirror)
			)
		)
		(property "Tolerance" "1%"
			(at 0 0 0)
			(layer "B.Fab")
			(hide yes)
			(effects
				(font
					(size 1 1)
					(thickness 0.15)
				)
				(justify mirror)
			)
		)
		(property "Val" "47k"
			(at 0 0 0)
			(layer "B.Fab")
			(hide yes)
			(effects
				(font
					(size 1 1)
					(thickness 0.15)
				)
				(justify mirror)
			)
		)
		(sheetname "/Supply/")
		(sheetfile "supply.kicad_sch")
		(attr smd)
		(fp_rect
			(start -0.93 0.47)
			(end 0.93 -0.47)
			(stroke
				(width 0.05)
				(type solid)
			)
			(fill no)
			(layer "B.CrtYd")
		)
		(fp_rect
			(start -0.5 0.25)
			(end 0.5 -0.25)
			(stroke
				(width 0.15)
				(type solid)
			)
			(fill no)
			(layer "B.Fab")
		)
		(pad "1" smd roundrect
			(at -0.485 0)
			(size 0.59 0.64)
			(layers "B.Cu" "B.Mask" "B.Paste")
			(roundrect_rratio 0.25)
			(net 221 "/Supply/EN1")
			(pintype "passive")
		)
		(pad "2" smd roundrect
			(at 0.485 0)
			(size 0.59 0.64)
			(layers "B.Cu" "B.Mask" "B.Paste")
			(roundrect_rratio 0.25)
			(net 41 "+3V3_AON")
			(pintype "passive")
		)
	)
	(footprint "antmicro-footprints:R_0402_1005Metric"
		(layer "B.Cu")
		(at 196.953499 152.8535 180)
		(descr "Resistor SMD 0402")
		(tags "resistor SMD 0402")
		(property "Reference" "R140"
			(at -1.122484 0.772697 0)
			(layer "B.SilkS")
			(hide yes)
			(effects
				(font
					(size 0.7 0.7)
					(thickness 0.15)
				)
				(justify left bottom mirror)
			)
		)
		(property "Value" "R_47k_0402"
			(at -1.011843 -1.772047 0)
			(layer "B.Fab")
			(effects
				(font
					(size 0.7 0.7)
					(thickness 0.15)
				)
				(justify left bottom mirror)
			)
		)
		(property "Datasheet" "https://www.bourns.com/docs/product-datasheets/cr.pdf"
			(at 0 0 180)
			(layer "F.Fab")
			(hide yes)
			(effects
				(font
					(size 1.27 1.27)
					(thickness 0.15)
				)
			)
		)
		(property "Author" "Antmicro"
			(at 393.906998 305.707 0)
			(layer "B.Fab")
			(hide yes)
			(effects
				(font
					(size 1 1)
					(thickness 0.15)
				)
				(justify mirror)
			)
		)
		(property "License" "Apache-2.0"
			(at 393.906998 305.707 0)
			(layer "B.Fab")
			(hide yes)
			(effects
				(font
					(size 1 1)
					(thickness 0.15)
				)
				(justify mirror)
			)
		)
		(property "MPN" "CR0402-FX-4702GLF"
			(at 393.906998 305.707 0)
			(layer "B.Fab")
			(hide yes)
			(effects
				(font
					(size 1 1)
					(thickness 0.15)
				)
				(justify mirror)
			)
		)
		(property "Manufacturer" "Bourns"
			(at 393.906998 305.707 0)
			(layer "B.Fab")
			(hide yes)
			(effects
				(font
					(size 1 1)
					(thickness 0.15)
				)
				(justify mirror)
			)
		)
		(property "Tolerance" "1%"
			(at 393.906998 305.707 0)
			(layer "B.Fab")
			(hide yes)
			(effects
				(font
					(size 1 1)
					(thickness 0.15)
				)
				(justify mirror)
			)
		)
		(property "Val" "47k"
			(at 393.906998 305.707 0)
			(layer "B.Fab")
			(hide yes)
			(effects
				(font
					(size 1 1)
					(thickness 0.15)
				)
				(justify mirror)
			)
		)
		(sheetname "/Supply/")
		(sheetfile "supply.kicad_sch")
		(attr smd)
		(fp_rect
			(start -0.93 0.47)
			(end 0.93 -0.47)
			(stroke
				(width 0.05)
				(type solid)
			)
			(fill no)
			(layer "B.CrtYd")
		)
		(fp_rect
			(start -0.5 0.25)
			(end 0.5 -0.25)
			(stroke
				(width 0.15)
				(type solid)
			)
			(fill no)
			(layer "B.Fab")
		)
		(pad "1" smd roundrect
			(at -0.485 0 180)
			(size 0.59 0.64)
			(layers "B.Cu" "B.Mask" "B.Paste")
			(roundrect_rratio 0.25)
			(net 687 "IN2")
			(pintype "passive")
		)
		(pad "2" smd roundrect
			(at 0.485 0 180)
			(size 0.59 0.64)
			(layers "B.Cu" "B.Mask" "B.Paste")
			(roundrect_rratio 0.25)
			(net 41 "+3V3_AON")
			(pintype "passive")
		)
	)
	(footprint "antmicro-footprints:C_0402_1005Metric"
		(layer "B.Cu")
		(at 127.375501 184.801 -90)
		(descr "Capacitor SMD 0402 (1005 Metric), square (rectangular) end terminal, IPC_7351 nominal, (Body size source: IPC-SM-782 page 76, https://www.pcb-3d.com/wordpress/wp-content/uploads/ipc-sm-782a_amendment_1_and_2.pdf)")
		(tags "capacitor 0402")
		(property "Reference" "C47"
			(at 0 1.17 90)
			(layer "B.SilkS")
			(hide yes)
			(effects
				(font
					(size 0.7 0.7)
					(thickness 0.15)
				)
				(justify left bottom mirror)
			)
		)
		(property "Value" "C_100n_0402"
			(at 0 -1.169 90)
			(layer "B.Fab")
			(effects
				(font
					(size 0.7 0.7)
					(thickness 0.15)
				)
				(justify left bottom mirror)
			)
		)
		(property "Datasheet" "https://www.murata.com/products/productdetail?partno=GRM155R61H104KE14%23"
			(at 0 0 270)
			(layer "F.Fab")
			(hide yes)
			(effects
				(font
					(size 1.27 1.27)
					(thickness 0.15)
				)
			)
		)
		(property "Author" "Antmicro"
			(at -57.425499 312.176501 0)
			(layer "B.Fab")
			(hide yes)
			(effects
				(font
					(size 1 1)
					(thickness 0.15)
				)
				(justify mirror)
			)
		)
		(property "Dielectric" "X5R"
			(at -57.425499 312.176501 0)
			(layer "B.Fab")
			(hide yes)
			(effects
				(font
					(size 1 1)
					(thickness 0.15)
				)
				(justify mirror)
			)
		)
		(property "License" "Apache-2.0"
			(at -57.425499 312.176501 0)
			(layer "B.Fab")
			(hide yes)
			(effects
				(font
					(size 1 1)
					(thickness 0.15)
				)
				(justify mirror)
			)
		)
		(property "MPN" "GRM155R61H104KE14D"
			(at -57.425499 312.176501 0)
			(layer "B.Fab")
			(hide yes)
			(effects
				(font
					(size 1 1)
					(thickness 0.15)
				)
				(justify mirror)
			)
		)
		(property "Manufacturer" "Murata"
			(at -57.425499 312.176501 0)
			(layer "B.Fab")
			(hide yes)
			(effects
				(font
					(size 1 1)
					(thickness 0.15)
				)
				(justify mirror)
			)
		)
		(property "Val" "100n"
			(at -57.425499 312.176501 0)
			(layer "B.Fab")
			(hide yes)
			(effects
				(font
					(size 1 1)
					(thickness 0.15)
				)
				(justify mirror)
			)
		)
		(property "Voltage" "50V"
			(at -57.425499 312.176501 0)
			(layer "B.Fab")
			(hide yes)
			(effects
				(font
					(size 1 1)
					(thickness 0.15)
				)
				(justify mirror)
			)
		)
		(sheetname "/FPGA power/")
		(sheetfile "fpga-power.kicad_sch")
		(attr smd)
		(fp_rect
			(start -0.9656 0.4572)
			(end 0.9652 -0.4828)
			(stroke
				(width 0.05)
				(type solid)
			)
			(fill no)
			(layer "B.CrtYd")
		)
		(fp_line
			(start -0.5 0.25)
			(end 0.498 0.25)
			(stroke
				(width 0.15)
				(type solid)
			)
			(layer "B.Fab")
		)
		(fp_line
			(start 0.498 0.25)
			(end 0.498 -0.248)
			(stroke
				(width 0.15)
				(type solid)
			)
			(layer "B.Fab")
		)
		(fp_line
			(start -0.5 -0.248)
			(end -0.5 0.25)
			(stroke
				(width 0.15)
				(type solid)
			)
			(layer "B.Fab")
		)
		(fp_line
			(start 0.498 -0.248)
			(end -0.5 -0.248)
			(stroke
				(width 0.15)
				(type solid)
			)
			(layer "B.Fab")
		)
		(pad "1" smd roundrect
			(at -0.5 0 180)
			(size 0.6 0.6)
			(layers "B.Cu" "B.Mask" "B.Paste")
			(roundrect_rratio 0.25)
			(net 1 "GND")
			(pintype "passive")
		)
		(pad "2" smd roundrect
			(at 0.498 0 270)
			(size 0.6 0.6)
			(layers "B.Cu" "B.Mask" "B.Paste")
			(roundrect_rratio 0.25)
			(net 200 "+3V3")
			(pintype "passive")
		)
	)
	(footprint "antmicro-footprints:C_0402_1005Metric"
		(layer "B.Cu")
		(at 103.34 176.204 90)
		(descr "Capacitor SMD 0402")
		(tags "capacitor SMD 0402")
		(property "Reference" "C235"
			(at 0 0.699 90)
			(layer "B.SilkS")
			(hide yes)
			(effects
				(font
					(size 0.7 0.7)
					(thickness 0.15)
				)
				(justify right bottom mirror)
			)
		)
		(property "Value" "C_100n_0402"
			(at -1.022927 -2.155213 90)
			(layer "B.Fab")
			(effects
				(font
					(size 0.7 0.7)
					(thickness 0.15)
				)
				(justify right bottom mirror)
			)
		)
		(property "Datasheet" "https://www.murata.com/products/productdetail?partno=GRM155R61H104KE14%23"
			(at 0 0 90)
			(layer "F.Fab")
			(hide yes)
			(effects
				(font
					(size 1.27 1.27)
					(thickness 0.15)
				)
			)
		)
		(property "Author" "Antmicro"
			(at 279.544 72.864 0)
			(layer "B.Fab")
			(hide yes)
			(effects
				(font
					(size 1 1)
					(thickness 0.15)
				)
				(justify mirror)
			)
		)
		(property "Dielectric" "X5R"
			(at 279.544 72.864 0)
			(layer "B.Fab")
			(hide yes)
			(effects
				(font
					(size 1 1)
					(thickness 0.15)
				)
				(justify mirror)
			)
		)
		(property "License" "Apache-2.0"
			(at 279.544 72.864 0)
			(layer "B.Fab")
			(hide yes)
			(effects
				(font
					(size 1 1)
					(thickness 0.15)
				)
				(justify mirror)
			)
		)
		(property "MPN" "GRM155R61H104KE14D"
			(at 279.544 72.864 0)
			(layer "B.Fab")
			(hide yes)
			(effects
				(font
					(size 1 1)
					(thickness 0.15)
				)
				(justify mirror)
			)
		)
		(property "Manufacturer" "Murata"
			(at 279.544 72.864 0)
			(layer "B.Fab")
			(hide yes)
			(effects
				(font
					(size 1 1)
					(thickness 0.15)
				)
				(justify mirror)
			)
		)
		(property "Val" "100n"
			(at 279.544 72.864 0)
			(layer "B.Fab")
			(hide yes)
			(effects
				(font
					(size 1 1)
					(thickness 0.15)
				)
				(justify mirror)
			)
		)
		(property "Voltage" "50V"
			(at 279.544 72.864 0)
			(layer "B.Fab")
			(hide yes)
			(effects
				(font
					(size 1 1)
					(thickness 0.15)
				)
				(justify mirror)
			)
		)
		(sheetname "/Debug FTDI/")
		(sheetfile "debug-ftdi.kicad_sch")
		(attr smd)
		(fp_rect
			(start -0.925 0.47)
			(end 0.925 -0.47)
			(stroke
				(width 0.05)
				(type default)
			)
			(fill no)
			(layer "B.CrtYd")
		)
		(fp_line
			(start 0.504 -0.248)
			(end -0.494 -0.248)
			(stroke
				(width 0.15)
				(type solid)
			)
			(layer "B.Fab")
		)
		(fp_line
			(start -0.494 -0.248)
			(end -0.494 0.25)
			(stroke
				(width 0.15)
				(type solid)
			)
			(layer "B.Fab")
		)
		(fp_line
			(start 0.504 0.25)
			(end 0.504 -0.248)
			(stroke
				(width 0.15)
				(type solid)
			)
			(layer "B.Fab")
		)
		(fp_line
			(start -0.494 0.25)
			(end 0.504 0.25)
			(stroke
				(width 0.15)
				(type solid)
			)
			(layer "B.Fab")
		)
		(pad "1" smd roundrect
			(at -0.48 0 90)
			(size 0.59 0.64)
			(layers "B.Cu" "B.Mask" "B.Paste")
			(roundrect_rratio 0.25)
			(net 1 "GND")
			(pintype "passive")
		)
		(pad "2" smd roundrect
			(at 0.48 0 90)
			(size 0.59 0.64)
			(layers "B.Cu" "B.Mask" "B.Paste")
			(roundrect_rratio 0.25)
			(net 6 "/Debug FTDI/FTDI_3V3")
			(pintype "passive")
		)
	)
)
